# T6G (Grand Teton) — schematic netlist excerpt (pin names and nets, part order shuffled) for the footprints in the layout excerpt that follows; sources: Cadence DE-HDL packaged netlist, KiCad conversion of 04192023_DAF0TMB3IC0_F0TG_MB_C_brd_V02_OCP.brd

PU32  ISL99390FRZTR5935  ISL99390FRZ-TR5935 IC  pkg QFN21_6X5XB  page 216
  VOS  = PVDDCR_SOC_P1_VOS3
  AGND  = GND
  VCC  = PVDDCR_SOC_P1_VCC3
  PVCC  = PVDDCR_CPU0_P1_PVCC
  PGND1  = GND
  GL1  = NC_PVDDCR_SOC_P1_GL1_3
  PGND2  = GND
  SW  = SW_PVDDCR_SOC_P1_SW3
  VIN1  = SW_P12V_AUX_PVDDCR_SOC_P1_FLT
  VIN2  = SW_P12V_AUX_PVDDCR_SOC_P1_FLT
  DNC  = NC_PVDDCR_SOC_P1_DNC3
  PHASE  = SW_PVDDCR_SOC_P1_PH3
  BOOT  = SW_PVDDCR_SOC_P1_BOOT3
  PWM  = PVDDCR_SOC_P1_PWM3
  EN  = PVDDCR_SOC_P1_VCC3
  TOUT_FLT  = PVDDCR_SOC_P1_TEMP1
  LSET  = PVDDCR_SOC_P1_LSET3
  IOUT  = PVDDCR_SOC_P1_IMON3
  REFIN  = PVDDCR_CPU0_P1_VCCS
  PGND3  = GND
  GL2  = NC_PVDDCR_SOC_P1_GL2_3

(kicad_pcb
	(version 20260206)
	(generator "pcbnew")
	(generator_version "10.0")
	(general
		(thickness 1.6)
		(legacy_teardrops no)
	)
	(paper "A4")
	(title_block
		(title "04192023_DAF0TMB3IC0_F0TG_MB_C_brd_V02_OCP.brd")
		(comment 1 "Grand Teton / footprints 2715-2715 of 8354")
	)
	(layers
		(0 "F.Cu" signal "TOP")
		(4 "In1.Cu" signal "GND")
		(6 "In2.Cu" signal "IN1")
		(8 "In3.Cu" signal "GND1")
		(10 "In4.Cu" signal "IN2")
		(12 "In5.Cu" signal "GND2")
		(14 "In6.Cu" signal "IN3")
		(16 "In7.Cu" signal "GND3")
		(18 "In8.Cu" signal "VCC")
		(20 "In9.Cu" signal "VCC1")
		(22 "In10.Cu" signal "GND4")
		(24 "In11.Cu" signal "IN4")
		(26 "In12.Cu" signal "GND5")
		(28 "In13.Cu" signal "IN5")
		(30 "In14.Cu" signal "GND6")
		(32 "In15.Cu" signal "IN6")
		(34 "In16.Cu" signal "GND7")
		(2 "B.Cu" signal "BOTTOM")
		(9 "F.Adhes" user "F.Adhesive")
		(11 "B.Adhes" user "B.Adhesive")
		(13 "F.Paste" user "Package Geometry/Pastemask Top")
		(15 "B.Paste" user "Package Geometry/Pastemask Bottom")
		(5 "F.SilkS" user "Ref Des/Silkscreen Top")
		(7 "B.SilkS" user "Ref Des/Silkscreen Bottom")
		(1 "F.Mask" user "Board Geometry/Soldermask Top")
		(3 "B.Mask" user "Board Geometry/Soldermask Bottom")
		(17 "Dwgs.User" user "User.Drawings")
		(19 "Cmts.User" user "User.Comments")
		(21 "Eco1.User" user "User.Eco1")
		(23 "Eco2.User" user "User.Eco2")
		(25 "Edge.Cuts" user "Board Geometry/Outline")
		(27 "Margin" user)
		(31 "F.CrtYd" user "Package Geometry/Place Bound Top")
		(29 "B.CrtYd" user "Package Geometry/Place Bound Bottom")
		(35 "F.Fab" user "Ref Des/Assembly Top")
		(33 "B.Fab" user "Ref Des/Assembly Bottom")
	)
	(footprint ""
		(layer "F.Cu")
		(at 132.42417 -156.531056 180)
		(property "Reference" "PU32"
			(at 6.086856 -5.12572 0)
			(unlocked yes)
			(layer "F.SilkS")
			(effects
				(font
					(size 0.7874 0.5842)
					(thickness 0.1524)
				)
				(justify left)
			)
		)
		(property "Value" ""
			(at 0 0 180)
			(layer "F.Fab")
			(effects
				(font
					(size 1.27 1.27)
				)
			)
		)
		(duplicate_pad_numbers_are_jumpers no)
		(fp_line
			(start 2.500122 2.999994)
			(end 2.2987 2.999994)
			(stroke
				(width 0.1524)
				(type default)
			)
			(layer "F.SilkS")
		)
		(fp_line
			(start 2.500122 2.339594)
			(end 2.500122 2.999994)
			(stroke
				(width 0.1524)
				(type default)
			)
			(layer "F.SilkS")
		)
		(fp_line
			(start 2.500122 -2.999994)
			(end 2.500122 -2.44348)
			(stroke
				(width 0.1524)
				(type default)
			)
			(layer "F.SilkS")
		)
		(fp_line
			(start 2.31394 -2.999994)
			(end 2.500122 -2.999994)
			(stroke
				(width 0.1524)
				(type default)
			)
			(layer "F.SilkS")
		)
		(fp_line
			(start -2.2987 2.999994)
			(end -2.500122 2.999994)
			(stroke
				(width 0.1524)
				(type default)
			)
			(layer "F.SilkS")
		)
		(fp_line
			(start -2.500122 2.999994)
			(end -2.500122 2.339594)
			(stroke
				(width 0.1524)
				(type default)
			)
			(layer "F.SilkS")
		)
		(fp_line
			(start -2.500122 0.6604)
			(end -2.500122 0.229108)
			(stroke
				(width 0.1524)
				(type default)
			)
			(layer "F.SilkS")
		)
		(fp_line
			(start -2.500122 -2.529078)
			(end -2.500122 -2.999994)
			(stroke
				(width 0.1524)
				(type default)
			)
			(layer "F.SilkS")
		)
		(fp_line
			(start -2.500122 -2.999994)
			(end -2.24409 -2.999994)
			(stroke
				(width 0.1524)
				(type default)
			)
			(layer "F.SilkS")
		)
		(fp_poly
			(pts
				(xy -2.710688 -2.451608) (xy -3.384296 -2.676144) (xy -2.935224 -3.125216)
			)
			(stroke
				(width 0)
				(type default)
			)
			(fill yes)
			(layer "F.SilkS")
		)
		(fp_line
			(start 2.500122 2.999994)
			(end -2.500122 2.999994)
			(stroke
				(width 0.1)
				(type default)
			)
			(layer "F.Fab")
		)
		(fp_line
			(start 2.500122 -2.999994)
			(end 2.500122 2.999994)
			(stroke
				(width 0.1)
				(type default)
			)
			(layer "F.Fab")
		)
		(fp_line
			(start -2.500122 2.999994)
			(end -2.500122 -2.999994)
			(stroke
				(width 0.1)
				(type default)
			)
			(layer "F.Fab")
		)
		(fp_line
			(start -2.500122 -2.999994)
			(end 2.500122 -2.999994)
			(stroke
				(width 0.1)
				(type default)
			)
			(layer "F.Fab")
		)
		(fp_poly
			(pts
				(xy -4.218432 -2.783078) (xy -4.218432 -1.767078) (xy -3.202432 -2.275078)
			)
			(stroke
				(width 0)
				(type default)
			)
			(fill yes)
			(layer "F.Fab")
		)
		(pad "1" smd rect
			(at -2.400046 -2.275078 270)
			(size 0.2286 0.6096)
			(layers "F.Cu" "F.Mask" "F.Paste")
			(net "PVDDCR_SOC_P1_VOS3")
		)
		(pad "2" smd rect
			(at -2.400046 -1.82499 270)
			(size 0.2286 0.6096)
			(layers "F.Cu" "F.Mask" "F.Paste")
			(net "GND")
		)
		(pad "3" smd rect
			(at -2.400046 -1.374902 270)
			(size 0.2286 0.6096)
			(layers "F.Cu" "F.Mask" "F.Paste")
			(net "PVDDCR_SOC_P1_VCC3")
		)
		(pad "4" smd rect
			(at -2.400046 -0.925068 270)
			(size 0.2286 0.6096)
			(layers "F.Cu" "F.Mask" "F.Paste")
			(net "PVDDCR_CPU0_P1_PVCC")
		)
		(pad "5" smd rect
			(at -2.400046 -0.47498 270)
			(size 0.2286 0.6096)
			(layers "F.Cu" "F.Mask" "F.Paste")
			(net "GND")
		)
		(pad "6" smd rect
			(at -2.400046 -0.024892 270)
			(size 0.2286 0.6096)
			(layers "F.Cu" "F.Mask" "F.Paste")
			(net "NC_PVDDCR_SOC_P1_GL1_3")
		)
		(pad "7_9-20_24" smd circle
			(at 0 1.150112 270)
			(size 0 0)
			(layers "F.Cu" "F.Mask" "F.Paste")
			(net "GND")
		)
		(pad "10_19" smd rect
			(at 0 2.899918 270)
			(size 0.6096 4.318)
			(layers "F.Cu" "F.Mask" "F.Paste")
			(net "SW_PVDDCR_SOC_P1_SW3")
		)
		(pad "25_29" smd rect
			(at 1.549908 -1.279906 90)
			(size 2.0574 2.3114)
			(layers "F.Cu" "F.Mask" "F.Paste")
			(net "SW_P12V_AUX_PVDDCR_SOC_P1_FLT")
		)
		(pad "30" smd rect
			(at 2.05994 -2.899918 180)
			(size 0.2286 0.6096)
			(layers "F.Cu" "F.Mask" "F.Paste")
			(net "SW_P12V_AUX_PVDDCR_SOC_P1_FLT")
		)
		(pad "31" smd rect
			(at 1.610106 -2.899918 180)
			(size 0.2286 0.6096)
			(layers "F.Cu" "F.Mask" "F.Paste")
			(net "NC_PVDDCR_SOC_P1_DNC3")
		)
		(pad "32" smd rect
			(at 1.160018 -2.899918 180)
			(size 0.2286 0.6096)
			(layers "F.Cu" "F.Mask" "F.Paste")
			(net "SW_PVDDCR_SOC_P1_PH3")
		)
		(pad "33" smd rect
			(at 0.70993 -2.899918 180)
			(size 0.2286 0.6096)
			(layers "F.Cu" "F.Mask" "F.Paste")
			(net "SW_PVDDCR_SOC_P1_BOOT3")
		)
		(pad "34" smd rect
			(at 0.260096 -2.899918 180)
			(size 0.2286 0.6096)
			(layers "F.Cu" "F.Mask" "F.Paste")
			(net "PVDDCR_SOC_P1_PWM3")
		)
		(pad "35" smd rect
			(at -0.189992 -2.899918 180)
			(size 0.2286 0.6096)
			(layers "F.Cu" "F.Mask" "F.Paste")
			(net "PVDDCR_SOC_P1_VCC3")
		)
		(pad "36" smd rect
			(at -0.64008 -2.899918 180)
			(size 0.2286 0.6096)
			(layers "F.Cu" "F.Mask" "F.Paste")
			(net "PVDDCR_SOC_P1_TEMP1")
		)
		(pad "37" smd rect
			(at -1.089914 -2.899918 180)
			(size 0.2286 0.6096)
			(layers "F.Cu" "F.Mask" "F.Paste")
			(net "PVDDCR_SOC_P1_LSET3")
		)
		(pad "38" smd rect
			(at -1.540002 -2.899918 180)
			(size 0.2286 0.6096)
			(layers "F.Cu" "F.Mask" "F.Paste")
			(net "PVDDCR_SOC_P1_IMON3")
		)
		(pad "39" smd rect
			(at -1.99009 -2.899918 180)
			(size 0.2286 0.6096)
			(layers "F.Cu" "F.Mask" "F.Paste")
			(net "PVDDCR_CPU0_P1_VCCS")
		)
		(pad "40" smd rect
			(at -0.87503 -1.27508 180)
			(size 1.7526 1.9558)
			(layers "F.Cu" "F.Mask" "F.Paste")
			(net "GND")
		)
		(pad "41" smd rect
			(at -1.525016 0.249936 90)
			(size 0.3048 0.4572)
			(layers "F.Cu" "F.Mask" "F.Paste")
			(net "NC_PVDDCR_SOC_P1_GL2_3")
		)
		(zone
			(layer "F.Cu")
			(hatch none 0.5)
			(connect_pads
				(clearance 0)
			)
			(min_thickness 0.25)
			(keepout
				(tracks not_allowed)
				(vias allowed)
				(pads allowed)
				(copperpour not_allowed)
				(footprints allowed)
			)
			(placement
				(enabled no)
				(sheetname "")
			)
			(fill
				(thermal_gap 0.5)
				(thermal_bridge_width 0.5)
				(island_removal_mode 0)
			)
			(polygon
				(pts
					(xy 134.924292 -159.075374) (xy 134.924292 -158.78175) (xy 129.924048 -158.78175) (xy 129.924048 -159.075374)
					(xy 130.21437 -159.075374) (xy 134.63397 -159.075374)
				)
			)
		)
		(zone
			(layer "F.Cu")
			(hatch none 0.5)
			(connect_pads
				(clearance 0)
			)
			(min_thickness 0.25)
			(keepout
				(tracks not_allowed)
				(vias allowed)
				(pads allowed)
				(copperpour not_allowed)
				(footprints allowed)
			)
			(placement
				(enabled no)
				(sheetname "")
			)
			(fill
				(thermal_gap 0.5)
				(thermal_bridge_width 0.5)
				(island_removal_mode 0)
			)
			(polygon
				(pts
					(xy 132.3721 -156.284676) (xy 132.3721 -154.227276) (xy 134.2263 -154.227276) (xy 134.2263 -154.468322)
					(xy 134.468616 -154.468322) (xy 134.468616 -153.986738) (xy 130.558794 -153.986738) (xy 130.558794 -154.17165)
					(xy 132.080762 -154.17165) (xy 132.080762 -156.33065) (xy 129.924048 -156.33065) (xy 129.924048 -156.580332)
					(xy 132.076444 -156.580332)
				)
			)
		)
	)
)
